# T6G (Grand Teton) — schematic parts with pin connectivity, parts 8081–8081 of 8303; source: Cadence DE-HDL packaged netlist (pstxprt.dat, pstxnet.dat, pstchip.dat)

U25  GENOA_SP5  SOCKET6096_13568-001 IO  pkg SOCKET6096_93-4X120-45XA  page 10  (pins 6049-6096 of 6096)
  Y26  VSS_Y26  POWER  = GND
  Y27  VSS_Y27  POWER  = GND
  Y28  VSS_Y28  POWER  = GND
  Y29  TEST5_CCD11  TRI  = TP_CPU0_TEST5_CCD11
  Y30  TEST5_CCD3  TRI  = TP_CPU0_TEST5_CCD3
  Y31  VSS_Y31  POWER  = GND
  Y32  VSS_Y32  POWER  = GND
  Y33  VSS_Y33  POWER  = GND
  Y34  VSS_Y34  POWER  = GND
  Y35  VDDCR_CPU0_Y35  POWER  = PVDDCR_CPU0_P0
  Y36  VDDCR_CPU0_Y36  POWER  = PVDDCR_CPU0_P0
  Y37  VSS_Y37  POWER  = GND
  Y39  VSS_Y39  POWER  = GND
  Y40  VDDCR_CPU0_Y40  POWER  = PVDDCR_CPU0_P0
  Y41  VDDCR_CPU0_Y41  POWER  = PVDDCR_CPU0_P0
  Y42  VSS_Y42  POWER  = GND
  Y43  VSS_Y43  POWER  = GND
  Y44  VSS_Y44  POWER  = GND
  Y45  VSS_Y45  POWER  = GND
  Y46  TEST6_CCD3  OUT  = TP_CPU0_TEST6_CCD3
  Y47  TEST5_CCD8  TRI  = TP_CPU0_TEST5_CCD8
  Y48  VSS_Y48  POWER  = GND
  Y49  VSS_Y49  POWER  = GND
  Y50  VSS_Y50  POWER  = GND
  Y51  VSS_Y51  POWER  = GND
  Y52  VSS_Y52  POWER  = GND
  Y53  VSS_Y53  POWER  = GND
  Y54  VSS_Y54  POWER  = GND
  Y55  MCA_DQS_L7  BI  = M_C_CPU0_SA_DQS_DN<7>
  Y56  MCA_DQS_L2  BI  = M_C_CPU0_SA_DQS_DN<2>
  Y57  VDDIO_Y57  POWER  = PVDDIO_P0
  Y58  MDA_DQS_L7  BI  = M_D_CPU0_SA_DQS_DN<7>
  Y59  VSS_Y59  POWER  = GND
  Y60  MDA_DQS_L2  BI  = M_D_CPU0_SA_DQS_DN<2>
  Y61  VSS_Y61  POWER  = GND
  Y62  MBA_DQS_L7  BI  = M_B_CPU0_SA_DQS_DN<7>
  Y63  MBA_DQS_L2  BI  = M_B_CPU0_SA_DQS_DN<2>
  Y64  VDDIO_Y64  POWER  = PVDDIO_P0
  Y65  MFA_DQS_L7  BI  = M_F_CPU0_SA_DQS_DN<7>
  Y66  VSS_Y66  POWER  = GND
  Y67  MFA_DQS_L2  BI  = M_F_CPU0_SA_DQS_DN<2>
  Y68  VSS_Y68  POWER  = GND
  Y69  MEA_DQS_L7  BI  = M_E_CPU0_SA_DQS_DN<7>
  Y70  MEA_DQS_L2  BI  = M_E_CPU0_SA_DQS_DN<2>
  Y71  VDDIO_Y71  POWER  = PVDDIO_P0
  Y72  MAA_DQS_L7  BI  = M_A_CPU0_SA_DQS_DN<7>
  Y73  VSS_Y73  POWER  = GND
  Y74  MAA_DQS_L2  BI  = M_A_CPU0_SA_DQS_DN<2>
